# TIMECARD (Time Appliance Project (Time Card)) — schematic netlist excerpt (pin names and nets, part order shuffled) for the footprints in the layout excerpt that follows; sources: Cadence DE-HDL packaged netlist, KiCad conversion of R4006-B0001-02_R01.brd

C179  CAPACITOR  47UF 4V 20%  pkg SMC_0805R_H057  page 14 : \1\ = XP1R0V_FPGA ; \2\ = SG
R253  RESISTOR  2.2OHM 1%  pkg SMC_0805R_H026  page 29 : \1\ = UNNAMED_523_CAPACITOR_I31_2 ; \2\ = SG

(kicad_pcb
	(version 20260206)
	(generator "pcbnew")
	(generator_version "10.0")
	(general
		(thickness 1.6)
		(legacy_teardrops no)
	)
	(paper "A4")
	(title_block
		(title "timecard-production-celestica-r4006 — R4006-B0001-02_R01.brd")
		(comment 1 "Time Appliance Project (Time Card) / footprints 884-885 of 1113")
	)
	(layers
		(0 "F.Cu" signal "TOP")
		(4 "In1.Cu" signal "L02_GND1")
		(6 "In2.Cu" signal "L03_SIG1")
		(8 "In3.Cu" signal "L04_GND2")
		(10 "In4.Cu" signal "L05_VCC1")
		(12 "In5.Cu" signal "L06_VCC2")
		(14 "In6.Cu" signal "L07_GND3")
		(16 "In7.Cu" signal "L08_SIG2")
		(18 "In8.Cu" signal "L09_GND4")
		(2 "B.Cu" signal "BOTTOM")
		(9 "F.Adhes" user "F.Adhesive")
		(11 "B.Adhes" user "B.Adhesive")
		(13 "F.Paste" user "Package Geometry/Pastemask Top")
		(15 "B.Paste" user "Package Geometry/Pastemask Bottom")
		(5 "F.SilkS" user "Ref Des/Silkscreen Top")
		(7 "B.SilkS" user "Ref Des/Silkscreen Bottom")
		(1 "F.Mask" user "Board Geometry/Soldermask Top")
		(3 "B.Mask" user "Board Geometry/Soldermask Bottom")
		(17 "Dwgs.User" user "User.Drawings")
		(19 "Cmts.User" user "User.Comments")
		(21 "Eco1.User" user "User.Eco1")
		(23 "Eco2.User" user "User.Eco2")
		(25 "Edge.Cuts" user "Board Geometry/Outline")
		(27 "Margin" user)
		(31 "F.CrtYd" user "Package Geometry/Place Bound Top")
		(29 "B.CrtYd" user "Package Geometry/Place Bound Bottom")
		(35 "F.Fab" user "Ref Des/Assembly Top")
		(33 "B.Fab" user "Ref Des/Assembly Bottom")
	)
	(footprint ""
		(layer "B.Cu")
		(at 145.288 -50.546 180)
		(property "Reference" "R253"
			(at -0.254 -1.81737 0)
			(unlocked yes)
			(layer "B.SilkS")
			(effects
				(font
					(size 0.7874 0.5842)
					(thickness 0.1524)
				)
				(justify mirror)
			)
		)
		(property "Value" "VAL*"
			(at -0.0508 3.159506 180)
			(unlocked yes)
			(layer "B.Fab")
			(hide yes)
			(effects
				(font
					(size 0.7874 0.5842)
					(thickness 0.1524)
				)
				(justify mirror)
			)
		)
		(property "Tolerance" "TOL*"
			(at -0.0508 4.124706 180)
			(unlocked yes)
			(layer "Cmts.User")
			(hide yes)
			(effects
				(font
					(size 0.7874 0.5842)
					(thickness 0.1524)
				)
				(justify mirror)
			)
		)
		(property "User Part Number" "PARTNUM*"
			(at -0.0508 5.089906 180)
			(unlocked yes)
			(layer "Cmts.User")
			(hide yes)
			(effects
				(font
					(size 0.7874 0.5842)
					(thickness 0.1524)
				)
				(justify mirror)
			)
		)
		(property "Device Type" "RESISTOR-G157-12R20-01,2.2OHM,A"
			(at 0 2.194306 180)
			(unlocked yes)
			(layer "B.Fab")
			(hide yes)
			(effects
				(font
					(size 0.7874 0.5842)
					(thickness 0.1524)
				)
				(justify mirror)
			)
		)
		(duplicate_pad_numbers_are_jumpers no)
		(fp_line
			(start 1.5748 0.9398)
			(end -1.5748 0.9398)
			(stroke
				(width 0.1)
				(type default)
			)
			(layer "B.SilkS")
		)
		(fp_line
			(start 1.5748 -0.9398)
			(end 1.5748 0.9398)
			(stroke
				(width 0.1)
				(type default)
			)
			(layer "B.SilkS")
		)
		(fp_line
			(start -1.5748 0.9398)
			(end -1.5748 -0.9398)
			(stroke
				(width 0.1)
				(type default)
			)
			(layer "B.SilkS")
		)
		(fp_line
			(start -1.5748 -0.9398)
			(end 1.5748 -0.9398)
			(stroke
				(width 0.1)
				(type default)
			)
			(layer "B.SilkS")
		)
		(fp_rect
			(start -1.5748 -0.9398)
			(end 1.5748 0.9398)
			(stroke
				(width 0)
				(type default)
			)
			(fill no)
			(layer "B.CrtYd")
		)
		(fp_line
			(start 1.016 0.635)
			(end -1.016 0.635)
			(stroke
				(width 0.1)
				(type default)
			)
			(layer "B.Fab")
		)
		(fp_line
			(start 1.016 -0.635)
			(end 1.016 0.635)
			(stroke
				(width 0.1)
				(type default)
			)
			(layer "B.Fab")
		)
		(fp_line
			(start -1.016 0.635)
			(end -1.016 -0.635)
			(stroke
				(width 0.1)
				(type default)
			)
			(layer "B.Fab")
		)
		(fp_line
			(start -1.016 -0.635)
			(end 1.016 -0.635)
			(stroke
				(width 0.1)
				(type default)
			)
			(layer "B.Fab")
		)
		(pad "1" smd rect
			(at 0.8382 0)
			(size 0.9652 1.3716)
			(layers "B.Cu" "B.Mask" "B.Paste")
			(net "UNNAMED_523_CAPACITOR_I31_2")
		)
		(pad "2" smd rect
			(at -0.8382 0)
			(size 0.9652 1.3716)
			(layers "B.Cu" "B.Mask" "B.Paste")
			(net "SG")
		)
		(zone
			(layer "B.Cu")
			(hatch none 0.5)
			(connect_pads
				(clearance 0)
			)
			(min_thickness 0.25)
			(keepout
				(tracks allowed)
				(vias not_allowed)
				(pads allowed)
				(copperpour not_allowed)
				(footprints allowed)
			)
			(placement
				(enabled no)
				(sheetname "")
			)
			(fill
				(thermal_gap 0.5)
				(thermal_bridge_width 0.5)
				(island_removal_mode 0)
			)
			(polygon
				(pts
					(xy 145.5166 -49.911) (xy 145.5166 -51.181) (xy 145.0594 -51.181) (xy 145.0594 -49.911)
				)
			)
		)
	)
	(footprint ""
		(layer "B.Cu")
		(at 137.16 -46.228 -90)
		(property "Reference" "C179"
			(at 0 -1.87833 270)
			(unlocked yes)
			(layer "B.SilkS")
			(effects
				(font
					(size 0.7874 0.5842)
					(thickness 0.1524)
				)
				(justify mirror)
			)
		)
		(property "Value" "VAL*"
			(at -0.0762 3.134106 270)
			(unlocked yes)
			(layer "B.Fab")
			(hide yes)
			(effects
				(font
					(size 0.7874 0.5842)
					(thickness 0.1524)
				)
				(justify mirror)
			)
		)
		(property "Tolerance" "TOL*"
			(at -0.0762 4.048506 270)
			(unlocked yes)
			(layer "Cmts.User")
			(hide yes)
			(effects
				(font
					(size 0.7874 0.5842)
					(thickness 0.1524)
				)
				(justify mirror)
			)
		)
		(property "User Part Number" "PARTNUM*"
			(at -0.1016 5.013706 270)
			(unlocked yes)
			(layer "Cmts.User")
			(hide yes)
			(effects
				(font
					(size 0.7874 0.5842)
					(thickness 0.1524)
				)
				(justify mirror)
			)
		)
		(property "Device Type" "CAPACITOR-G107-0F476-AM,47UF,2A"
			(at -0.0508 2.194306 270)
			(unlocked yes)
			(layer "B.Fab")
			(hide yes)
			(effects
				(font
					(size 0.7874 0.5842)
					(thickness 0.1524)
				)
				(justify mirror)
			)
		)
		(duplicate_pad_numbers_are_jumpers no)
		(fp_line
			(start -1.5748 0.9398)
			(end -1.5748 -0.9398)
			(stroke
				(width 0.1)
				(type default)
			)
			(layer "B.SilkS")
		)
		(fp_line
			(start 1.5748 0.9398)
			(end -1.5748 0.9398)
			(stroke
				(width 0.1)
				(type default)
			)
			(layer "B.SilkS")
		)
		(fp_line
			(start -1.5748 -0.9398)
			(end 1.5748 -0.9398)
			(stroke
				(width 0.1)
				(type default)
			)
			(layer "B.SilkS")
		)
		(fp_line
			(start 1.5748 -0.9398)
			(end 1.5748 0.9398)
			(stroke
				(width 0.1)
				(type default)
			)
			(layer "B.SilkS")
		)
		(fp_rect
			(start 1.5748 0.9398)
			(end -1.5748 -0.9398)
			(stroke
				(width 0)
				(type default)
			)
			(fill no)
			(layer "B.CrtYd")
		)
		(fp_line
			(start -1.016 0.635)
			(end -1.016 -0.635)
			(stroke
				(width 0.1)
				(type default)
			)
			(layer "B.Fab")
		)
		(fp_line
			(start 1.016 0.635)
			(end -1.016 0.635)
			(stroke
				(width 0.1)
				(type default)
			)
			(layer "B.Fab")
		)
		(fp_line
			(start -1.016 -0.635)
			(end 1.016 -0.635)
			(stroke
				(width 0.1)
				(type default)
			)
			(layer "B.Fab")
		)
		(fp_line
			(start 1.016 -0.635)
			(end 1.016 0.635)
			(stroke
				(width 0.1)
				(type default)
			)
			(layer "B.Fab")
		)
		(pad "1" smd rect
			(at 0.8382 0 90)
			(size 0.9652 1.3716)
			(layers "B.Cu" "B.Mask" "B.Paste")
			(net "XP1R0V_FPGA")
		)
		(pad "2" smd rect
			(at -0.8382 0 90)
			(size 0.9652 1.3716)
			(layers "B.Cu" "B.Mask" "B.Paste")
			(net "SG")
		)
		(zone
			(layer "B.Cu")
			(hatch none 0.5)
			(connect_pads
				(clearance 0)
			)
			(min_thickness 0.25)
			(keepout
				(tracks allowed)
				(vias not_allowed)
				(pads allowed)
				(copperpour not_allowed)
				(footprints allowed)
			)
			(placement
				(enabled no)
				(sheetname "")
			)
			(fill
				(thermal_gap 0.5)
				(thermal_bridge_width 0.5)
				(island_removal_mode 0)
			)
			(polygon
				(pts
					(xy 136.525 -45.9994) (xy 137.795 -45.9994) (xy 137.795 -46.4566) (xy 136.525 -46.4566)
				)
			)
		)
	)
)
